FILE_TYPE = CONNECTIVITY;
{Allegro Design Entry HDL 16.6-p007 (v16-6-112F) 10/10/2012}
"PAGE_NUMBER" = 91;
0"NC";
1"GND\g";
2"PVPP_ABC\g";
3"PVPP_ABC\g";
4"PVPP_ABC\g";
5"P3V3\g";
6"GND\g";
7"TP_HFI_IO_CONN0_RSVD_17";
8"PWRGD_PVPP_ABC";
9"FM_MODPRST_HFI0_CPU0_LVT2_N";
10"LED_HFI0_CPU0_N";
11"FM_MODPRST_HFI1_CPU0_LVT2_N";
12"LED_HFI1_CPU0_N";
13"SMB_HFI1_CPU0_LVC2_SCL";
14"SMB_OCP_FRU_STBY_LVC3_SCL";
15"SMB_OCP_FRU_STBY_LVC3_SDA";
16"RST_HFI0_CPU0_LVT2_N";
17"IRQ_HFI0_CPU0_LVT2_N";
18"IRQ_HFI1_CPU0_LVT2_N";
19"RST_HFI1_CPU0_LVT2_N";
20"SMB_HFI1_CPU0_LVC2_SDA";
21"SMB_HFI0_CPU0_LVC2_SCL";
22"SMB_HFI0_CPU0_LVC2_SDA";
%"SCONN24_H46321001"
"1","(25,2825)","0","mstr_sconn","I1";
;
ROOM"HFI"
CDS_LOCATION"J8B1"
$SEC"1"
CDS_SEC"1"
CDS_LIB"mstr_sconn"
PACK_TYPE"SM"
MATERIAL"SCONN"
PART_NUMBER"H46321-001"
LOCATION"J8B1";
"MP1"
$PN"MP1"1;
"MP2"
$PN"MP2"6;
"IO1"
$PN"1"1;
"IO10"
$PN"10"13;
"IO11"
$PN"11"11;
"IO12"
$PN"12"20;
"IO13"
$PN"13"12;
"IO14"
$PN"14"19;
"IO15"
$PN"15"1;
"IO16"
$PN"16"18;
"IO17"
$PN"17"7;
"IO18"
$PN"18"5;
"IO19"
$PN"19"8;
"IO2"
$PN"2"21;
"IO20"
$PN"20"5;
"IO21"
$PN"21"3;
"IO22"
$PN"22"14;
"IO23"
$PN"23"1;
"IO24"
$PN"24"15;
"IO3"
$PN"3"9;
"IO4"
$PN"4"22;
"IO5"
$PN"5"10;
"IO6"
$PN"6"16;
"IO7"
$PN"7"1;
"IO8"
$PN"8"17;
"IO9"
$PN"9"1;
%"RES"
"2","(1400,3350)","0","mstr_discrete","I14";
;
CDS_SEC"1"
ROOM"HFI"
CDS_LOCATION"R8B8"
SEC"1"
SIGNAL_MODEL"DEFAULT_RESISTOR_4750OHM_2_1"
SEC_TYPE"0402"
CDS_LIB"mstr_discrete"
WATTAGE"1/16W"
MATERIAL"CHIP"
PACK_TYPE"0402"
TOLERANCE"1%"
VALUE"4.75K"
PART_NUMBER"G21796-072"
LOCATION"R8B8";
"A"
$PN"1"4;
"B"
$PN"2"16;
%"RES"
"2","(1150,3350)","0","mstr_discrete","I16";
;
CDS_SEC"1"
ROOM"HFI"
CDS_LOCATION"R8B10"
SEC"1"
SIGNAL_MODEL"DEFAULT_RESISTOR_4750OHM_2_1"
SEC_TYPE"0402"
CDS_LIB"mstr_discrete"
WATTAGE"1/16W"
MATERIAL"CHIP"
PACK_TYPE"0402"
TOLERANCE"1%"
VALUE"4.75K"
PART_NUMBER"G21796-072"
LOCATION"R8B10";
"A"
$PN"1"4;
"B"
$PN"2"17;
%"RES"
"2","(900,3350)","0","mstr_discrete","I17";
;
CDS_SEC"1"
ROOM"HFI"
CDS_LOCATION"R8B16"
SEC"1"
SIGNAL_MODEL"DEFAULT_RESISTOR_4750OHM_2_1"
SEC_TYPE"0402"
CDS_LIB"mstr_discrete"
WATTAGE"1/16W"
MATERIAL"CHIP"
PACK_TYPE"0402"
TOLERANCE"1%"
VALUE"4.75K"
PART_NUMBER"G21796-072"
LOCATION"R8B16";
"A"
$PN"1"4;
"B"
$PN"2"19;
%"RES"
"2","(650,3350)","0","mstr_discrete","I18";
;
CDS_SEC"1"
ROOM"HFI"
CDS_LOCATION"R8B17"
SEC"1"
CDS_LIB"mstr_discrete"
SEC_TYPE"0402"
SIGNAL_MODEL"DEFAULT_RESISTOR_4750OHM_2_1"
WATTAGE"1/16W"
MATERIAL"CHIP"
PACK_TYPE"0402"
TOLERANCE"1%"
VALUE"4.75K"
PART_NUMBER"G21796-072"
LOCATION"R8B17";
"A"
$PN"1"4;
"B"
$PN"2"18;
%"GND"
"1","(-475,2325)","0","mstr_symbols","I2";
;
HDL_POWER"GND"
BODY_TYPE"PLUMBING"
SIZE"1B"
CDS_LIB"mstr_symbols"
VOLTAGE"0.0V";
"A\NAC"1;
%"RES"
"2","(-600,3325)","2","mstr_discrete","I20";
;
CDS_SEC"1"
ROOM"HFI"
CDS_LOCATION"R8B18"
SEC"1"
SEC_TYPE"0402"
CDS_LIB"mstr_discrete"
SIGNAL_MODEL"DEFAULT_RESISTOR_4750OHM_2_1"
WATTAGE"1/16W"
MATERIAL"CHIP"
PACK_TYPE"0402"
TOLERANCE"1%"
VALUE"4.75K"
PART_NUMBER"G21796-072"
LOCATION"R8B18";
"A"
$PN"1"2;
"B"
$PN"2"12;
%"RES"
"2","(-975,3325)","2","mstr_discrete","I21";
;
CDS_SEC"1"
ROOM"HFI"
CDS_LOCATION"R8B19"
SEC"1"
SEC_TYPE"0402"
CDS_LIB"mstr_discrete"
SIGNAL_MODEL"DEFAULT_RESISTOR_4750OHM_2_1"
WATTAGE"1/16W"
MATERIAL"CHIP"
PACK_TYPE"0402"
TOLERANCE"1%"
VALUE"4.75K"
PART_NUMBER"G21796-072"
LOCATION"R8B19";
"A"
$PN"1"2;
"B"
$PN"2"11;
%"RES"
"2","(-1350,3325)","2","mstr_discrete","I22";
;
CDS_SEC"1"
ROOM"HFI"
CDS_LOCATION"R8B5"
SEC"1"
SEC_TYPE"0402"
CDS_LIB"mstr_discrete"
SIGNAL_MODEL"DEFAULT_RESISTOR_4750OHM_2_1"
WATTAGE"1/16W"
MATERIAL"CHIP"
PACK_TYPE"0402"
TOLERANCE"1%"
VALUE"4.75K"
PART_NUMBER"G21796-072"
LOCATION"R8B5";
"A"
$PN"1"2;
"B"
$PN"2"10;
%"RES"
"2","(-1725,3325)","2","mstr_discrete","I24";
;
CDS_SEC"1"
ROOM"HFI"
CDS_LOCATION"R8B3"
SEC"1"
SEC_TYPE"0402"
CDS_LIB"mstr_discrete"
SIGNAL_MODEL"DEFAULT_RESISTOR_4750OHM_2_1"
WATTAGE"1/16W"
MATERIAL"CHIP"
PACK_TYPE"0402"
TOLERANCE"1%"
VALUE"4.75K"
PART_NUMBER"G21796-072"
LOCATION"R8B3";
"A"
$PN"1"2;
"B"
$PN"2"9;
%"PVPP_ABC"
"1","(-1725,3625)","0","mstr_symbols","I30";
;
HDL_POWER"PVPP_ABC"
ROOM"PVPP_KLM_VR"
BODY_TYPE"PLUMBING"
CDS_LIB"mstr_symbols"
BOM_COST"PVPP_KLM_VR"
VOLTAGE"2.5V";
"G\NAC"2;
%"PVPP_ABC"
"1","(-525,3625)","0","mstr_symbols","I31";
;
HDL_POWER"PVPP_ABC"
ROOM"PVPP_KLM_VR"
BODY_TYPE"PLUMBING"
CDS_LIB"mstr_symbols"
BOM_COST"PVPP_KLM_VR"
VOLTAGE"2.5V";
"G\NAC"3;
%"PVPP_ABC"
"1","(2400,3675)","0","mstr_symbols","I32";
;
HDL_POWER"PVPP_ABC"
ROOM"PVPP_KLM_VR"
BODY_TYPE"PLUMBING"
CDS_LIB"mstr_symbols"
BOM_COST"PVPP_KLM_VR"
VOLTAGE"2.5V";
"G\NAC"4;
%"P3V3"
"1","(575,3625)","0","mstr_symbols","I33";
;
HDL_POWER"P3V3"
BODY_TYPE"PLUMBING"
SIZE"1B"
CDS_LIB"mstr_symbols"
VOLTAGE"3.3V";
"G\NAC"5;
%"RES"
"2","(1650,3350)","0","mstr_discrete","I34";
;
CDS_SEC"1"
ROOM"SMBUS_CPU0_STL"
CDS_LOCATION"R8B13"
SEC"1"
SEC_TYPE"0402"
CDS_LIB"mstr_discrete"
WATTAGE"1/16W"
MATERIAL"CHIP"
PACK_TYPE"0402"
TOLERANCE"1%"
VALUE"1.8K"
PART_NUMBER"G21796-336"
LOCATION"R8B13";
"A"
$PN"1"4;
"B"
$PN"2"20;
%"RES"
"2","(1875,3350)","0","mstr_discrete","I35";
;
CDS_SEC"1"
ROOM"SMBUS_CPU0_STL"
CDS_LOCATION"R8B11"
SEC"1"
SEC_TYPE"0402"
CDS_LIB"mstr_discrete"
WATTAGE"1/16W"
MATERIAL"CHIP"
PACK_TYPE"0402"
TOLERANCE"1%"
VALUE"1.8K"
PART_NUMBER"G21796-336"
LOCATION"R8B11";
"A"
$PN"1"4;
"B"
$PN"2"13;
%"RES"
"2","(2125,3350)","0","mstr_discrete","I36";
;
CDS_SEC"1"
ROOM"SMBUS_CPU0_STL"
CDS_LOCATION"R8B7"
SEC"1"
SEC_TYPE"0402"
CDS_LIB"mstr_discrete"
WATTAGE"1/16W"
MATERIAL"CHIP"
PACK_TYPE"0402"
TOLERANCE"1%"
VALUE"1.8K"
PART_NUMBER"G21796-336"
LOCATION"R8B7";
"A"
$PN"1"4;
"B"
$PN"2"22;
%"RES"
"2","(2400,3350)","0","mstr_discrete","I37";
;
CDS_SEC"1"
ROOM"SMBUS_CPU0_STL"
CDS_LOCATION"R8B6"
SEC"1"
SEC_TYPE"0402"
CDS_LIB"mstr_discrete"
WATTAGE"1/16W"
MATERIAL"CHIP"
PACK_TYPE"0402"
TOLERANCE"1%"
VALUE"1.8K"
PART_NUMBER"G21796-336"
LOCATION"R8B6";
"A"
$PN"1"4;
"B"
$PN"2"21;
%"GND"
"1","(525,2325)","0","mstr_symbols","I38";
;
HDL_POWER"GND"
BODY_TYPE"PLUMBING"
CDS_LIB"mstr_symbols"
SIZE"1B"
VOLTAGE"0.0V";
"A\NAC"6;
END.
